(kicad_pcb
	(version 20241229)
	(generator "pcbnew")
	(generator_version "9.0")
	(general
		(thickness 1.61)
		(legacy_teardrops no)
	)
	(paper "A3")
	(title_block
		(title "RDIMM DDR5 Tester")
		(date "2026-05-21")
		(rev "2.2.0")
		(company "Antmicro")
		(comment 9 "footprints 166-169 of 796")
	)
	(layers
		(0 "F.Cu" signal)
		(4 "In1.Cu" power)
		(6 "In2.Cu" mixed)
		(8 "In3.Cu" power)
		(10 "In4.Cu" mixed)
		(12 "In5.Cu" power)
		(14 "In6.Cu" mixed)
		(16 "In7.Cu" power)
		(18 "In8.Cu" power)
		(20 "In9.Cu" mixed)
		(22 "In10.Cu" power)
		(2 "B.Cu" signal)
		(9 "F.Adhes" user "F.Adhesive")
		(11 "B.Adhes" user "B.Adhesive")
		(13 "F.Paste" user)
		(15 "B.Paste" user)
		(5 "F.SilkS" user "F.Silkscreen")
		(7 "B.SilkS" user "B.Silkscreen")
		(1 "F.Mask" user)
		(3 "B.Mask" user)
		(17 "Dwgs.User" user "User.Drawings")
		(19 "Cmts.User" user "User.Comments")
		(21 "Eco1.User" user "User.Eco1")
		(23 "Eco2.User" user "User.Eco2")
		(25 "Edge.Cuts" user)
		(27 "Margin" user)
		(31 "F.CrtYd" user "F.Courtyard")
		(29 "B.CrtYd" user "B.Courtyard")
		(35 "F.Fab" user)
		(33 "B.Fab" user)
	)
	(footprint "antmicro-footprints:LED_0402_1005Metric_G"
		(layer "F.Cu")
		(at 116.48 139.083 -90)
		(property "Reference" "D17"
			(at -1.033 -0.37 90)
			(unlocked yes)
			(layer "F.SilkS")
			(effects
				(font
					(size 0.7 0.7)
					(thickness 0.15)
				)
				(justify left bottom)
			)
		)
		(property "Value" "LED_G_0402_VLMTG1500-GS08"
			(at 0 1.5 270)
			(unlocked yes)
			(layer "F.Fab")
			(effects
				(font
					(size 0.7 0.7)
					(thickness 0.15)
				)
				(justify left bottom)
			)
		)
		(property "Datasheet" "https://www.vishay.com/docs/82554/vlmo1500.pdf"
			(at 0 0 90)
			(layer "F.Fab")
			(hide yes)
			(effects
				(font
					(size 1.27 1.27)
					(thickness 0.15)
				)
			)
		)
		(property "MPN" "VLMTG1500-GS08"
			(at 0 0 270)
			(unlocked yes)
			(layer "F.Fab")
			(hide yes)
			(effects
				(font
					(size 1 1)
					(thickness 0.15)
				)
			)
		)
		(property "Manufacturer" "Vishay"
			(at 0 0 270)
			(unlocked yes)
			(layer "F.Fab")
			(hide yes)
			(effects
				(font
					(size 1 1)
					(thickness 0.15)
				)
			)
		)
		(property "Color" "Green"
			(at 0 0 270)
			(unlocked yes)
			(layer "F.Fab")
			(hide yes)
			(effects
				(font
					(size 1 1)
					(thickness 0.15)
				)
			)
		)
		(property "Author" "Antmicro"
			(at 0 0 270)
			(unlocked yes)
			(layer "F.Fab")
			(hide yes)
			(effects
				(font
					(size 1 1)
					(thickness 0.15)
				)
			)
		)
		(property "License" "Apache-2.0"
			(at 0 0 270)
			(unlocked yes)
			(layer "F.Fab")
			(hide yes)
			(effects
				(font
					(size 1 1)
					(thickness 0.15)
				)
			)
		)
		(sheetname "/Debug FTDI + VNA/")
		(sheetfile "debug-ftdi.kicad_sch")
		(attr smd)
		(fp_line
			(start -0.175 0.4)
			(end 0.175 0.4)
			(stroke
				(width 0.15)
				(type solid)
			)
			(layer "F.SilkS")
		)
		(fp_line
			(start -0.9 -0.4)
			(end -0.9 0.4)
			(stroke
				(width 0.15)
				(type solid)
			)
			(layer "F.SilkS")
		)
		(fp_line
			(start -0.175 -0.4)
			(end 0.175 -0.4)
			(stroke
				(width 0.15)
				(type solid)
			)
			(layer "F.SilkS")
		)
		(fp_rect
			(start -0.925 -0.47)
			(end 0.925 0.47)
			(stroke
				(width 0.05)
				(type default)
			)
			(fill no)
			(layer "F.CrtYd")
		)
		(fp_line
			(start -0.489 0.26)
			(end -0.158 0.26)
			(stroke
				(width 0.15)
				(type solid)
			)
			(layer "F.Fab")
		)
		(fp_line
			(start -0.489 0.26)
			(end 0.501 0.26)
			(stroke
				(width 0.15)
				(type solid)
			)
			(layer "F.Fab")
		)
		(fp_line
			(start -0.158 0.26)
			(end -0.158 -0.248)
			(stroke
				(width 0.15)
				(type solid)
			)
			(layer "F.Fab")
		)
		(fp_line
			(start 0.172 0.26)
			(end 0.501 0.26)
			(stroke
				(width 0.15)
				(type solid)
			)
			(layer "F.Fab")
		)
		(fp_line
			(start 0.501 0.26)
			(end 0.501 -0.248)
			(stroke
				(width 0.15)
				(type solid)
			)
			(layer "F.Fab")
		)
		(fp_line
			(start 0.501 0.26)
			(end 0.501 -0.248)
			(stroke
				(width 0.15)
				(type solid)
			)
			(layer "F.Fab")
		)
		(fp_line
			(start -0.173 0.202)
			(end -0.173 0.102)
			(stroke
				(width 0.15)
				(type solid)
			)
			(layer "F.Fab")
		)
		(fp_line
			(start 0.228 0.202)
			(end 0.228 0)
			(stroke
				(width 0.15)
				(type solid)
			)
			(layer "F.Fab")
		)
		(fp_line
			(start -0.074 0)
			(end 0.228 0.202)
			(stroke
				(width 0.15)
				(type solid)
			)
			(layer "F.Fab")
		)
		(fp_line
			(start 0.228 0)
			(end 0.228 -0.202)
			(stroke
				(width 0.15)
				(type solid)
			)
			(layer "F.Fab")
		)
		(fp_line
			(start -0.173 -0.202)
			(end -0.173 0.102)
			(stroke
				(width 0.15)
				(type solid)
			)
			(layer "F.Fab")
		)
		(fp_line
			(start 0.228 -0.202)
			(end -0.074 0)
			(stroke
				(width 0.15)
				(type solid)
			)
			(layer "F.Fab")
		)
		(fp_line
			(start -0.489 -0.248)
			(end -0.489 0.26)
			(stroke
				(width 0.15)
				(type solid)
			)
			(layer "F.Fab")
		)
		(fp_line
			(start -0.489 -0.248)
			(end -0.489 0.26)
			(stroke
				(width 0.15)
				(type solid)
			)
			(layer "F.Fab")
		)
		(fp_line
			(start -0.158 -0.248)
			(end -0.489 -0.248)
			(stroke
				(width 0.15)
				(type solid)
			)
			(layer "F.Fab")
		)
		(fp_line
			(start 0.172 -0.248)
			(end 0.172 0.26)
			(stroke
				(width 0.15)
				(type solid)
			)
			(layer "F.Fab")
		)
		(fp_line
			(start 0.501 -0.248)
			(end -0.489 -0.248)
			(stroke
				(width 0.15)
				(type solid)
			)
			(layer "F.Fab")
		)
		(fp_line
			(start 0.501 -0.248)
			(end 0.172 -0.248)
			(stroke
				(width 0.15)
				(type solid)
			)
			(layer "F.Fab")
		)
		(fp_text user "Author: Antmicro"
			(at 0 4.15 270)
			(layer "F.Fab")
			(effects
				(font
					(size 0.7 0.7)
					(thickness 0.15)
				)
				(justify left bottom)
			)
		)
		(fp_text user "${REFERENCE}"
			(at 0 2.95 270)
			(unlocked yes)
			(layer "F.Fab")
			(effects
				(font
					(size 0.7 0.7)
					(thickness 0.15)
				)
				(justify left bottom)
			)
		)
		(fp_text user "License: Apache-2.0"
			(at 0 5.35 270)
			(layer "F.Fab")
			(effects
				(font
					(size 0.7 0.7)
					(thickness 0.15)
				)
				(justify left bottom)
			)
		)
		(pad "1" smd roundrect
			(at -0.48 0 270)
			(size 0.59 0.64)
			(layers "F.Cu" "F.Mask" "F.Paste")
			(roundrect_rratio 0.25)
			(net 220 "Net-(D17-C)")
			(pinfunction "C")
			(pintype "passive")
		)
		(pad "2" smd roundrect
			(at 0.48 0 270)
			(size 0.59 0.64)
			(layers "F.Cu" "F.Mask" "F.Paste")
			(roundrect_rratio 0.25)
			(net 818 "Net-(D17-A)")
			(pinfunction "A")
			(pintype "passive")
		)
	)
	(footprint "antmicro-footprints:R_1206_3216Metric"
		(layer "F.Cu")
		(at 256.6 179.775 180)
		(property "Reference" "R151"
			(at 5 -0.275 180)
			(layer "F.SilkS")
			(effects
				(font
					(size 0.7 0.7)
					(thickness 0.15)
				)
				(justify left bottom)
			)
		)
		(property "Value" "R_0R01_1206"
			(at -2.422356 2.103591 180)
			(layer "F.Fab")
			(effects
				(font
					(size 0.7 0.7)
					(thickness 0.15)
				)
				(justify left bottom)
			)
		)
		(property "Datasheet" "https://www.yageo.com/upload/media/product/productsearch/datasheet/rchip/PYu-RL_Group_521_RoHS_L_2.pdf"
			(at 0 0 180)
			(layer "F.Fab")
			(hide yes)
			(effects
				(font
					(size 1.27 1.27)
					(thickness 0.15)
				)
			)
		)
		(property "Manufacturer" "YAGEO"
			(at 0 0 180)
			(unlocked yes)
			(layer "F.Fab")
			(hide yes)
			(effects
				(font
					(size 1 1)
					(thickness 0.15)
				)
			)
		)
		(property "MPN" "RL1206FR-7W0R01L"
			(at 0 0 180)
			(unlocked yes)
			(layer "F.Fab")
			(hide yes)
			(effects
				(font
					(size 1 1)
					(thickness 0.15)
				)
			)
		)
		(property "Val" "0R01"
			(at 0 0 180)
			(unlocked yes)
			(layer "F.Fab")
			(hide yes)
			(effects
				(font
					(size 1 1)
					(thickness 0.15)
				)
			)
		)
		(property "License" "Apache-2.0"
			(at 0 0 180)
			(unlocked yes)
			(layer "F.Fab")
			(hide yes)
			(effects
				(font
					(size 1 1)
					(thickness 0.15)
				)
			)
		)
		(property "Author" "Antmicro"
			(at 0 0 180)
			(unlocked yes)
			(layer "F.Fab")
			(hide yes)
			(effects
				(font
					(size 1 1)
					(thickness 0.15)
				)
			)
		)
		(property "Tolerance" "1%"
			(at 0 0 180)
			(unlocked yes)
			(layer "F.Fab")
			(hide yes)
			(effects
				(font
					(size 1 1)
					(thickness 0.15)
				)
			)
		)
		(sheetname "/Supply/DC-DC AUX, MGT/")
		(sheetfile "dc-dc-aux-mgt.kicad_sch")
		(attr smd)
		(fp_line
			(start 0.8 0.901)
			(end -0.8 0.901)
			(stroke
				(width 0.15)
				(type solid)
			)
			(layer "F.SilkS")
		)
		(fp_line
			(start 0.8 -0.899)
			(end -0.8 -0.899)
			(stroke
				(width 0.15)
				(type solid)
			)
			(layer "F.SilkS")
		)
		(fp_rect
			(start -2.325 -1.15)
			(end 2.325 1.15)
			(stroke
				(width 0.05)
				(type default)
			)
			(fill no)
			(layer "F.CrtYd")
		)
		(fp_line
			(start 1.6 -0.802)
			(end 1.6 0.8)
			(stroke
				(width 0.15)
				(type solid)
			)
			(layer "F.Fab")
		)
		(fp_line
			(start -1.601 0.8)
			(end 1.6 0.8)
			(stroke
				(width 0.15)
				(type solid)
			)
			(layer "F.Fab")
		)
		(fp_line
			(start -1.601 -0.802)
			(end 1.6 -0.802)
			(stroke
				(width 0.15)
				(type solid)
			)
			(layer "F.Fab")
		)
		(fp_line
			(start -1.601 -0.802)
			(end -1.601 0.8)
			(stroke
				(width 0.15)
				(type solid)
			)
			(layer "F.Fab")
		)
		(fp_text user "License: Apache-2.0"
			(at -2.401 6.3 180)
			(layer "F.Fab")
			(effects
				(font
					(size 0.7 0.7)
					(thickness 0.15)
				)
				(justify left bottom)
			)
		)
		(fp_text user "${REFERENCE}"
			(at -2.401 3.5 180)
			(layer "F.Fab")
			(effects
				(font
					(size 0.7 0.7)
					(thickness 0.15)
				)
				(justify left bottom)
			)
		)
		(fp_text user "Author: Antmicro"
			(at -2.401 4.899 180)
			(layer "F.Fab")
			(effects
				(font
					(size 0.7 0.7)
					(thickness 0.15)
				)
				(justify left bottom)
			)
		)
		(pad "1" smd roundrect
			(at -1.5 0.001 180)
			(size 1.15 1.8)
			(layers "F.Cu" "F.Mask" "F.Paste")
			(roundrect_rratio 0.25)
			(net 225 "/Supply/DC-DC AUX, MGT/MGTAVCCAUX_local")
			(pintype "passive")
		)
		(pad "2" smd roundrect
			(at 1.5 0.001 180)
			(size 1.15 1.8)
			(layers "F.Cu" "F.Mask" "F.Paste")
			(roundrect_rratio 0.25)
			(net 573 "+1V8_MGTVCCAUX")
			(pintype "passive")
		)
	)
	(footprint "antmicro-footprints:TP_SMD_1mm"
		(layer "F.Cu")
		(at 118.231 175.369)
		(property "Reference" "TP2"
			(at -2.65 0.65 0)
			(layer "F.SilkS")
			(hide yes)
			(effects
				(font
					(size 0.7 0.7)
					(thickness 0.15)
				)
				(justify left bottom)
			)
		)
		(property "Value" "TP_1mm_SMD"
			(at 0 1.4 0)
			(layer "F.Fab")
			(effects
				(font
					(size 0.7 0.7)
					(thickness 0.15)
				)
				(justify left bottom)
			)
		)
		(property "MPN" ""
			(at 0 0 0)
			(unlocked yes)
			(layer "F.Fab")
			(hide yes)
			(effects
				(font
					(size 1 1)
					(thickness 0.15)
				)
			)
		)
		(property "Manufacturer" ""
			(at 0 0 0)
			(unlocked yes)
			(layer "F.Fab")
			(hide yes)
			(effects
				(font
					(size 1 1)
					(thickness 0.15)
				)
			)
		)
		(property "Author" "Antmicro"
			(at 0 0 0)
			(unlocked yes)
			(layer "F.Fab")
			(hide yes)
			(effects
				(font
					(size 1 1)
					(thickness 0.15)
				)
			)
		)
		(property "License" "Apache-2.0"
			(at 0 0 0)
			(unlocked yes)
			(layer "F.Fab")
			(hide yes)
			(effects
				(font
					(size 1 1)
					(thickness 0.15)
				)
			)
		)
		(sheetname "/HDMI + SD Card/")
		(sheetfile "hdmi-sd-card.kicad_sch")
		(attr exclude_from_pos_files)
		(fp_circle
			(center 0 0)
			(end 0.6 0)
			(stroke
				(width 0.05)
				(type default)
			)
			(fill no)
			(layer "F.CrtYd")
		)
		(fp_text user "Author: Antmicro"
			(at -0.5 4 0)
			(layer "F.Fab")
			(effects
				(font
					(size 0.7 0.7)
					(thickness 0.15)
				)
				(justify left bottom)
			)
		)
		(fp_text user "License: Apache-2.0"
			(at -0.5 5.2 0)
			(layer "F.Fab")
			(effects
				(font
					(size 0.7 0.7)
					(thickness 0.15)
				)
				(justify left bottom)
			)
		)
		(fp_text user "${REFERENCE}"
			(at -0.5 2.8 0)
			(layer "F.Fab")
			(effects
				(font
					(size 0.7 0.7)
					(thickness 0.15)
				)
				(justify left bottom)
			)
		)
		(pad "1" smd circle
			(at 0 0)
			(size 1 1)
			(layers "F.Cu" "F.Mask")
			(net 8 "/HDMI + SD Card/HDMI_CONN_5V")
			(pinfunction "1")
			(pintype "passive")
		)
	)
	(footprint "antmicro-footprints:SOT-583"
		(layer "F.Cu")
		(at 123.45 163.25 90)
		(property "Reference" "U43"
			(at 1.525 3.2 0)
			(layer "F.SilkS")
			(effects
				(font
					(size 0.7 0.7)
					(thickness 0.15)
				)
				(justify left bottom)
			)
		)
		(property "Value" "TPS2116DRLR"
			(at 0 2.3 90)
			(layer "F.Fab")
			(effects
				(font
					(size 0.7 0.7)
					(thickness 0.15)
				)
				(justify left bottom)
			)
		)
		(property "Datasheet" "https://www.ti.com/lit/ds/symlink/tps2116.pdf?ts=1647438832100&ref_url=https%253A%252F%252Fwww.ti.com%252Fproduct%252FTPS2116"
			(at 0 0 90)
			(layer "F.Fab")
			(hide yes)
			(effects
				(font
					(size 1.27 1.27)
					(thickness 0.15)
				)
			)
		)
		(property "Manufacturer" "Texas Instruments"
			(at 0 0 90)
			(unlocked yes)
			(layer "F.Fab")
			(hide yes)
			(effects
				(font
					(size 1 1)
					(thickness 0.15)
				)
			)
		)
		(property "MPN" "TPS2116DRLR"
			(at 0 0 90)
			(unlocked yes)
			(layer "F.Fab")
			(hide yes)
			(effects
				(font
					(size 1 1)
					(thickness 0.15)
				)
			)
		)
		(property "Author" "Antmicro"
			(at 0 0 90)
			(unlocked yes)
			(layer "F.Fab")
			(hide yes)
			(effects
				(font
					(size 1 1)
					(thickness 0.15)
				)
			)
		)
		(property "License" "Apache-2.0"
			(at 0 0 90)
			(unlocked yes)
			(layer "F.Fab")
			(hide yes)
			(effects
				(font
					(size 1 1)
					(thickness 0.15)
				)
			)
		)
		(property ki_fp_filters "DRL0008A-MFG")
		(sheetname "/HDMI + SD Card/")
		(sheetfile "hdmi-sd-card.kicad_sch")
		(attr smd)
		(fp_line
			(start -0.65 -1.15)
			(end 0.65 -1.15)
			(stroke
				(width 0.15)
				(type solid)
			)
			(layer "F.SilkS")
		)
		(fp_line
			(start -0.651 1.15)
			(end 0.651 1.15)
			(stroke
				(width 0.15)
				(type solid)
			)
			(layer "F.SilkS")
		)
		(fp_circle
			(center -0.9 -1.1)
			(end -0.85 -1.05)
			(stroke
				(width 0.15)
				(type solid)
			)
			(fill yes)
			(layer "F.SilkS")
		)
		(fp_rect
			(start -1.15 -1.3)
			(end 1.15 1.3)
			(stroke
				(width 0.05)
				(type solid)
			)
			(fill no)
			(layer "F.CrtYd")
		)
		(fp_line
			(start -0.651 -1.1005)
			(end 0.651 -1.1005)
			(stroke
				(width 0.15)
				(type solid)
			)
			(layer "F.Fab")
		)
		(fp_line
			(start 0.651 1.1005)
			(end 0.651 -1.1005)
			(stroke
				(width 0.15)
				(type solid)
			)
			(layer "F.Fab")
		)
		(fp_line
			(start -0.651 1.1005)
			(end -0.651 -1.1005)
			(stroke
				(width 0.15)
				(type solid)
			)
			(layer "F.Fab")
		)
		(fp_line
			(start -0.651 1.1005)
			(end 0.651 1.1005)
			(stroke
				(width 0.15)
				(type solid)
			)
			(layer "F.Fab")
		)
		(fp_text user "License: Apache-2.0"
			(at -0.06 6.025 90)
			(layer "F.Fab")
			(effects
				(font
					(size 0.7 0.7)
					(thickness 0.15)
				)
				(justify left bottom)
			)
		)
		(fp_text user "${REFERENCE}"
			(at -0.06 4.025 90)
			(layer "F.Fab")
			(effects
				(font
					(size 0.7 0.7)
					(thickness 0.15)
				)
				(justify left bottom)
			)
		)
		(fp_text user "Author: Antmicro"
			(at -0.06 5.025 90)
			(layer "F.Fab")
			(effects
				(font
					(size 0.7 0.7)
					(thickness 0.15)
				)
				(justify left bottom)
			)
		)
		(pad "1" smd roundrect
			(at -0.739 -0.7495 90)
			(size 0.670001 0.299999)
			(layers "F.Cu" "F.Mask" "F.Paste")
			(roundrect_rratio 0.25)
			(net 1 "GND")
			(pinfunction "GND")
			(pintype "power_in")
		)
		(pad "2" smd roundrect
			(at -0.739 -0.2505 90)
			(size 0.670001 0.299999)
			(layers "F.Cu" "F.Mask" "F.Paste")
			(roundrect_rratio 0.25)
			(net 647 "/HDMI + SD Card/VCCB")
			(pinfunction "VOUT")
			(pintype "power_out")
		)
		(pad "3" smd roundrect
			(at -0.739 0.2495 90)
			(size 0.670001 0.299999)
			(layers "F.Cu" "F.Mask" "F.Paste")
			(roundrect_rratio 0.25)
			(net 797 "+1V8")
			(pinfunction "VIN1")
			(pintype "power_in")
		)
		(pad "4" smd roundrect
			(at -0.739 0.7495 90)
			(size 0.670001 0.299999)
			(layers "F.Cu" "F.Mask" "F.Paste")
			(roundrect_rratio 0.25)
			(net 772 "SD_SEL")
			(pinfunction "PR1")
			(pintype "input")
		)
		(pad "5" smd roundrect
			(at 0.74 0.7495 90)
			(size 0.670001 0.299999)
			(layers "F.Cu" "F.Mask" "F.Paste")
			(roundrect_rratio 0.25)
			(net 151 "+3V3")
			(pinfunction "MODE")
			(pintype "input")
		)
		(pad "6" smd roundrect
			(at 0.74 0.2495 90)
			(size 0.670001 0.299999)
			(layers "F.Cu" "F.Mask" "F.Paste")
			(roundrect_rratio 0.25)
			(net 151 "+3V3")
			(pinfunction "VIN2")
			(pintype "power_in")
		)
		(pad "7" smd roundrect
			(at 0.74 -0.2505 90)
			(size 0.670001 0.299999)
			(layers "F.Cu" "F.Mask" "F.Paste")
			(roundrect_rratio 0.25)
			(net 647 "/HDMI + SD Card/VCCB")
			(pinfunction "VOUT")
			(pintype "passive")
		)
		(pad "8" smd roundrect
			(at 0.74 -0.7495 90)
			(size 0.670001 0.299999)
			(layers "F.Cu" "F.Mask" "F.Paste")
			(roundrect_rratio 0.25)
			(net 663 "Net-(U43-ST)")
			(pinfunction "ST")
			(pintype "output")
		)
	)
)
